(kicad_pcb
	(version 20260206)
	(generator "pcbnew")
	(generator_version "10.0")
	(general
		(thickness 1.6)
		(legacy_teardrops no)
	)
	(paper "A4")
	(title_block
		(title "baseboard — 13948-1b.1110WZS1818.brd")
		(comment 1 "Honey Badger (Wiwynn) / footprints 1855-1863 of 2523")
	)
	(layers
		(0 "F.Cu" signal "TOP")
		(4 "In1.Cu" signal "L2GND")
		(6 "In2.Cu" signal "L3")
		(8 "In3.Cu" signal "L4VCC")
		(10 "In4.Cu" signal "L5VCC")
		(12 "In5.Cu" signal "L6")
		(14 "In6.Cu" signal "L7GND")
		(2 "B.Cu" signal "BOTTOM")
		(9 "F.Adhes" user "F.Adhesive")
		(11 "B.Adhes" user "B.Adhesive")
		(13 "F.Paste" user "Package Geometry/Pastemask Top")
		(15 "B.Paste" user "Package Geometry/Pastemask Bottom")
		(5 "F.SilkS" user "Ref Des/Silkscreen Top")
		(7 "B.SilkS" user "Ref Des/Silkscreen Bottom")
		(1 "F.Mask" user "Board Geometry/Soldermask Top")
		(3 "B.Mask" user "Board Geometry/Soldermask Bottom")
		(17 "Dwgs.User" user "User.Drawings")
		(19 "Cmts.User" user "User.Comments")
		(21 "Eco1.User" user "User.Eco1")
		(23 "Eco2.User" user "User.Eco2")
		(25 "Edge.Cuts" user "Board Geometry/Outline")
		(27 "Margin" user)
		(31 "F.CrtYd" user "Package Geometry/Place Bound Top")
		(29 "B.CrtYd" user "Package Geometry/Place Bound Bottom")
		(35 "F.Fab" user "Ref Des/Assembly Top")
		(33 "B.Fab" user "Ref Des/Assembly Bottom")
	)
	(footprint ""
		(layer "B.Cu")
		(at 325.374 -179.705)
		(property "Reference" "R5768"
			(at 0 0 0)
			(layer "B.SilkS")
			(hide yes)
			(effects
				(font
					(size 1.27 1.27)
				)
				(justify mirror)
			)
		)
		(property "Value" "1KR2F-3-GP"
			(at -0.064008 -3.993896 0)
			(unlocked yes)
			(layer "B.Fab")
			(hide yes)
			(effects
				(font
					(size 1.016 1.016)
					(thickness 0.1524)
				)
				(justify mirror)
			)
		)
		(property "Device Type" "R402H16"
			(at -0.064008 -5.517896 0)
			(unlocked yes)
			(layer "B.Fab")
			(hide yes)
			(effects
				(font
					(size 1.016 1.016)
					(thickness 0.1524)
				)
				(justify mirror)
			)
		)
		(duplicate_pad_numbers_are_jumpers no)
		(fp_line
			(start -0.508 -0.9398)
			(end 0.508 -0.9398)
			(stroke
				(width 0.1524)
				(type default)
			)
			(layer "B.SilkS")
		)
		(fp_line
			(start 0.508 -0.9398)
			(end 0.508 0.9398)
			(stroke
				(width 0.1524)
				(type default)
			)
			(layer "B.SilkS")
		)
		(fp_rect
			(start 0.508 0.9398)
			(end -0.508 -0.9398)
			(stroke
				(width 0)
				(type default)
			)
			(fill no)
			(layer "B.CrtYd")
		)
		(fp_rect
			(start 0.508 0.9398)
			(end -0.508 -0.9398)
			(stroke
				(width 0)
				(type default)
			)
			(fill no)
			(layer "B.Fab")
		)
		(pad "1" smd custom
			(at 0 -0.4445 180)
			(size 0.1397 0.1397)
			(layers "B.Cu" "B.Mask" "B.Paste")
			(net "P3V3_STBY")
			(options
				(clearance outline)
				(anchor circle)
			)
			(primitives
				(gr_poly
					(pts
						(arc
							(start -0.1778 0.2794)
							(mid -0.249642 0.249642)
							(end -0.2794 0.1778)
						)
						(arc
							(start -0.2794 -0.1778)
							(mid -0.249642 -0.249642)
							(end -0.1778 -0.2794)
						)
						(arc
							(start 0.1778 -0.2794)
							(mid 0.249642 -0.249642)
							(end 0.2794 -0.1778)
						)
						(arc
							(start 0.2794 0.1778)
							(mid 0.249642 0.249642)
							(end 0.1778 0.2794)
						)
					)
					(width 0)
					(fill yes)
				)
			)
		)
		(pad "2" smd custom
			(at 0 0.4445 180)
			(size 0.1397 0.1397)
			(layers "B.Cu" "B.Mask" "B.Paste")
			(net "ADC_P3V3_STBY")
			(options
				(clearance outline)
				(anchor circle)
			)
			(primitives
				(gr_poly
					(pts
						(arc
							(start -0.1778 0.2794)
							(mid -0.249642 0.249642)
							(end -0.2794 0.1778)
						)
						(arc
							(start -0.2794 -0.1778)
							(mid -0.249642 -0.249642)
							(end -0.1778 -0.2794)
						)
						(arc
							(start 0.1778 -0.2794)
							(mid 0.249642 -0.249642)
							(end 0.2794 -0.1778)
						)
						(arc
							(start 0.2794 0.1778)
							(mid 0.249642 0.249642)
							(end 0.1778 0.2794)
						)
					)
					(width 0)
					(fill yes)
				)
			)
		)
	)
	(footprint ""
		(layer "B.Cu")
		(at 33.478216 -232.33888)
		(property "Reference" "R510"
			(at 0 0 0)
			(layer "B.SilkS")
			(hide yes)
			(effects
				(font
					(size 1.27 1.27)
				)
				(justify mirror)
			)
		)
		(property "Value" "0R2J-2-GP"
			(at -0.064008 -3.993896 0)
			(unlocked yes)
			(layer "B.Fab")
			(hide yes)
			(effects
				(font
					(size 1.016 1.016)
					(thickness 0.1524)
				)
				(justify mirror)
			)
		)
		(property "Device Type" "R402H16"
			(at -0.064008 -5.517896 0)
			(unlocked yes)
			(layer "B.Fab")
			(hide yes)
			(effects
				(font
					(size 1.016 1.016)
					(thickness 0.1524)
				)
				(justify mirror)
			)
		)
		(duplicate_pad_numbers_are_jumpers no)
		(fp_line
			(start -0.508 -0.9398)
			(end 0.508 -0.9398)
			(stroke
				(width 0.1524)
				(type default)
			)
			(layer "B.SilkS")
		)
		(fp_line
			(start 0.508 -0.9398)
			(end 0.508 0.9398)
			(stroke
				(width 0.1524)
				(type default)
			)
			(layer "B.SilkS")
		)
		(fp_rect
			(start 0.508 0.9398)
			(end -0.508 -0.9398)
			(stroke
				(width 0)
				(type default)
			)
			(fill no)
			(layer "B.CrtYd")
		)
		(fp_rect
			(start 0.508 0.9398)
			(end -0.508 -0.9398)
			(stroke
				(width 0)
				(type default)
			)
			(fill no)
			(layer "B.Fab")
		)
		(pad "1" smd custom
			(at 0 -0.4445 180)
			(size 0.1397 0.1397)
			(layers "B.Cu" "B.Mask" "B.Paste")
			(net "SAS_HDD_PWR8_PCIE")
			(options
				(clearance outline)
				(anchor circle)
			)
			(primitives
				(gr_poly
					(pts
						(arc
							(start -0.1778 0.2794)
							(mid -0.249642 0.249642)
							(end -0.2794 0.1778)
						)
						(arc
							(start -0.2794 -0.1778)
							(mid -0.249642 -0.249642)
							(end -0.1778 -0.2794)
						)
						(arc
							(start 0.1778 -0.2794)
							(mid 0.249642 -0.249642)
							(end 0.2794 -0.1778)
						)
						(arc
							(start 0.2794 0.1778)
							(mid 0.249642 0.249642)
							(end 0.1778 0.2794)
						)
					)
					(width 0)
					(fill yes)
				)
			)
		)
		(pad "2" smd custom
			(at 0 0.4445 180)
			(size 0.1397 0.1397)
			(layers "B.Cu" "B.Mask" "B.Paste")
			(net "SAS_HDD_PWR8")
			(options
				(clearance outline)
				(anchor circle)
			)
			(primitives
				(gr_poly
					(pts
						(arc
							(start -0.1778 0.2794)
							(mid -0.249642 0.249642)
							(end -0.2794 0.1778)
						)
						(arc
							(start -0.2794 -0.1778)
							(mid -0.249642 -0.249642)
							(end -0.1778 -0.2794)
						)
						(arc
							(start 0.1778 -0.2794)
							(mid 0.249642 -0.249642)
							(end 0.2794 -0.1778)
						)
						(arc
							(start 0.2794 0.1778)
							(mid 0.249642 0.249642)
							(end 0.1778 0.2794)
						)
					)
					(width 0)
					(fill yes)
				)
			)
		)
	)
	(footprint ""
		(layer "B.Cu")
		(at 183.577992 -27.305 -90)
		(property "Reference" "C227"
			(at 0 0 90)
			(layer "B.SilkS")
			(hide yes)
			(effects
				(font
					(size 1.27 1.27)
				)
				(justify mirror)
			)
		)
		(property "Value" "SC10U6D3V5KX-1GP"
			(at 0.0762 -6.1214 270)
			(unlocked yes)
			(layer "B.Fab")
			(hide yes)
			(effects
				(font
					(size 1.016 1.016)
					(thickness 0.1524)
				)
				(justify mirror)
			)
		)
		(property "Device Type" "C805H54"
			(at 0.0762 -8.1534 270)
			(unlocked yes)
			(layer "B.Fab")
			(hide yes)
			(effects
				(font
					(size 1.016 1.016)
					(thickness 0.1524)
				)
				(justify mirror)
			)
		)
		(duplicate_pad_numbers_are_jumpers no)
		(fp_line
			(start -0.635 0)
			(end 0.635 0)
			(stroke
				(width 0.508)
				(type default)
			)
			(layer "B.SilkS")
		)
		(fp_rect
			(start 0.9652 1.778)
			(end -0.9652 -1.778)
			(stroke
				(width 0)
				(type default)
			)
			(fill no)
			(layer "B.CrtYd")
		)
		(fp_poly
			(pts
				(xy 0.9652 -1.778) (xy -0.9652 -1.778) (xy -0.9652 1.778) (xy 0.9652 1.778)
			)
			(stroke
				(width 0)
				(type default)
			)
			(fill no)
			(layer "B.Fab")
		)
		(pad "1" smd rect
			(at 0 -0.9652 90)
			(size 1.397 1.143)
			(layers "B.Cu" "B.Mask" "B.Paste")
			(net "P3V3_STBY")
		)
		(pad "2" smd rect
			(at 0 0.9652 90)
			(size 1.397 1.143)
			(layers "B.Cu" "B.Mask" "B.Paste")
			(net "GND")
		)
	)
	(footprint ""
		(layer "B.Cu")
		(at 187.895992 -33.909)
		(property "Reference" "C226"
			(at 0 0 0)
			(layer "B.SilkS")
			(hide yes)
			(effects
				(font
					(size 1.27 1.27)
				)
				(justify mirror)
			)
		)
		(property "Value" "SC10U6D3V5KX-1GP"
			(at 0.0762 -6.1214 0)
			(unlocked yes)
			(layer "B.Fab")
			(hide yes)
			(effects
				(font
					(size 1.016 1.016)
					(thickness 0.1524)
				)
				(justify mirror)
			)
		)
		(property "Device Type" "C805H54"
			(at 0.0762 -8.1534 0)
			(unlocked yes)
			(layer "B.Fab")
			(hide yes)
			(effects
				(font
					(size 1.016 1.016)
					(thickness 0.1524)
				)
				(justify mirror)
			)
		)
		(duplicate_pad_numbers_are_jumpers no)
		(fp_line
			(start -0.635 0)
			(end 0.635 0)
			(stroke
				(width 0.508)
				(type default)
			)
			(layer "B.SilkS")
		)
		(fp_rect
			(start 0.9652 1.778)
			(end -0.9652 -1.778)
			(stroke
				(width 0)
				(type default)
			)
			(fill no)
			(layer "B.CrtYd")
		)
		(fp_poly
			(pts
				(xy 0.9652 -1.778) (xy -0.9652 -1.778) (xy -0.9652 1.778) (xy 0.9652 1.778)
			)
			(stroke
				(width 0)
				(type default)
			)
			(fill no)
			(layer "B.Fab")
		)
		(pad "1" smd rect
			(at 0 -0.9652 180)
			(size 1.397 1.143)
			(layers "B.Cu" "B.Mask" "B.Paste")
			(net "P3V3_STBY")
		)
		(pad "2" smd rect
			(at 0 0.9652 180)
			(size 1.397 1.143)
			(layers "B.Cu" "B.Mask" "B.Paste")
			(net "GND")
		)
	)
	(footprint ""
		(layer "B.Cu")
		(at 15.995904 -100.400866)
		(property "Reference" "C134"
			(at 0 0 0)
			(layer "B.SilkS")
			(hide yes)
			(effects
				(font
					(size 1.27 1.27)
				)
				(justify mirror)
			)
		)
		(property "Value" "SCD01U50V2KX-1GP"
			(at -1.1811 -2.7051 0)
			(unlocked yes)
			(layer "B.Fab")
			(hide yes)
			(effects
				(font
					(size 1.016 1.016)
					(thickness 0.1524)
				)
				(justify mirror)
			)
		)
		(property "Device Type" "C402H22"
			(at -1.1811 -4.2291 0)
			(unlocked yes)
			(layer "B.Fab")
			(hide yes)
			(effects
				(font
					(size 1.016 1.016)
					(thickness 0.1524)
				)
				(justify mirror)
			)
		)
		(duplicate_pad_numbers_are_jumpers no)
		(fp_rect
			(start 0.4318 0.9525)
			(end -0.4318 -0.9525)
			(stroke
				(width 0)
				(type default)
			)
			(fill no)
			(layer "B.CrtYd")
		)
		(fp_rect
			(start 0.4318 0.9525)
			(end -0.4318 -0.9525)
			(stroke
				(width 0)
				(type default)
			)
			(fill no)
			(layer "B.Fab")
		)
		(pad "1" smd custom
			(at 0 -0.4445 180)
			(size 0.1524 0.1524)
			(layers "B.Cu" "B.Mask" "B.Paste")
			(net "IOC_SAS_RX_P6")
			(options
				(clearance outline)
				(anchor circle)
			)
			(primitives
				(gr_poly
					(pts
						(arc
							(start 0.3048 0.2032)
							(mid 0.275042 0.275042)
							(end 0.2032 0.3048)
						)
						(arc
							(start -0.2032 0.3048)
							(mid -0.275042 0.275042)
							(end -0.3048 0.2032)
						)
						(arc
							(start -0.3048 -0.2032)
							(mid -0.275042 -0.275042)
							(end -0.2032 -0.3048)
						)
						(arc
							(start 0.2032 -0.3048)
							(mid 0.275042 -0.275042)
							(end 0.3048 -0.2032)
						)
					)
					(width 0)
					(fill yes)
				)
			)
		)
		(pad "2" smd custom
			(at 0 0.4445 180)
			(size 0.1524 0.1524)
			(layers "B.Cu" "B.Mask" "B.Paste")
			(net "SAS_EXT_CONN_RX18_P")
			(options
				(clearance outline)
				(anchor circle)
			)
			(primitives
				(gr_poly
					(pts
						(arc
							(start 0.3048 0.2032)
							(mid 0.275042 0.275042)
							(end 0.2032 0.3048)
						)
						(arc
							(start -0.2032 0.3048)
							(mid -0.275042 0.275042)
							(end -0.3048 0.2032)
						)
						(arc
							(start -0.3048 -0.2032)
							(mid -0.275042 -0.275042)
							(end -0.2032 -0.3048)
						)
						(arc
							(start 0.2032 -0.3048)
							(mid 0.275042 -0.275042)
							(end 0.3048 -0.2032)
						)
					)
					(width 0)
					(fill yes)
				)
			)
		)
	)
	(footprint ""
		(layer "B.Cu")
		(at 120.30837 -95.1992 90)
		(property "Reference" "SC1144"
			(at 0 0 90)
			(layer "B.SilkS")
			(hide yes)
			(effects
				(font
					(size 1.27 1.27)
				)
				(justify mirror)
			)
		)
		(property "Value" "SCD1U6D3V1KX-GP"
			(at 2.8321 -1.7399 90)
			(unlocked yes)
			(layer "B.Fab")
			(hide yes)
			(effects
				(font
					(size 1.016 1.016)
					(thickness 0.1524)
				)
				(justify mirror)
			)
		)
		(property "Device Type" "C0201H13"
			(at 2.8321 -3.2639 90)
			(unlocked yes)
			(layer "B.Fab")
			(hide yes)
			(effects
				(font
					(size 1.016 1.016)
					(thickness 0.1524)
				)
				(justify mirror)
			)
		)
		(duplicate_pad_numbers_are_jumpers no)
		(fp_rect
			(start 0.2794 0.6477)
			(end -0.2794 -0.6477)
			(stroke
				(width 0)
				(type default)
			)
			(fill no)
			(layer "B.CrtYd")
		)
		(fp_rect
			(start 0.2794 0.6477)
			(end -0.2794 -0.6477)
			(stroke
				(width 0)
				(type default)
			)
			(fill no)
			(layer "B.Fab")
		)
		(pad "1" smd custom
			(at 0 -0.2794 270)
			(size 0.0762 0.0762)
			(layers "B.Cu" "B.Mask" "B.Paste")
			(net "GB_VDDH2")
			(options
				(clearance outline)
				(anchor circle)
			)
			(primitives
				(gr_poly
					(pts
						(arc
							(start 0.1524 0.127)
							(mid 0.137521 0.162921)
							(end 0.1016 0.1778)
						)
						(arc
							(start -0.1016 0.1778)
							(mid -0.137521 0.162921)
							(end -0.1524 0.127)
						)
						(arc
							(start -0.1524 -0.127)
							(mid -0.137521 -0.162921)
							(end -0.1016 -0.1778)
						)
						(arc
							(start 0.1016 -0.1778)
							(mid 0.137521 -0.162921)
							(end 0.1524 -0.127)
						)
					)
					(width 0)
					(fill yes)
				)
			)
		)
		(pad "2" smd custom
			(at 0 0.2794 270)
			(size 0.0762 0.0762)
			(layers "B.Cu" "B.Mask" "B.Paste")
			(net "GND")
			(options
				(clearance outline)
				(anchor circle)
			)
			(primitives
				(gr_poly
					(pts
						(arc
							(start 0.1524 0.127)
							(mid 0.137521 0.162921)
							(end 0.1016 0.1778)
						)
						(arc
							(start -0.1016 0.1778)
							(mid -0.137521 0.162921)
							(end -0.1524 0.127)
						)
						(arc
							(start -0.1524 -0.127)
							(mid -0.137521 -0.162921)
							(end -0.1016 -0.1778)
						)
						(arc
							(start 0.1016 -0.1778)
							(mid 0.137521 -0.162921)
							(end 0.1524 -0.127)
						)
					)
					(width 0)
					(fill yes)
				)
			)
		)
	)
	(footprint ""
		(layer "B.Cu")
		(at 141.97457 -93.9546)
		(property "Reference" "R5315"
			(at 0 0 0)
			(layer "B.SilkS")
			(hide yes)
			(effects
				(font
					(size 1.27 1.27)
				)
				(justify mirror)
			)
		)
		(property "Value" "0R2J-2-GP"
			(at -0.064008 -3.993896 0)
			(unlocked yes)
			(layer "B.Fab")
			(hide yes)
			(effects
				(font
					(size 1.016 1.016)
					(thickness 0.1524)
				)
				(justify mirror)
			)
		)
		(property "Device Type" "R402H16"
			(at -0.064008 -5.517896 0)
			(unlocked yes)
			(layer "B.Fab")
			(hide yes)
			(effects
				(font
					(size 1.016 1.016)
					(thickness 0.1524)
				)
				(justify mirror)
			)
		)
		(duplicate_pad_numbers_are_jumpers no)
		(fp_line
			(start -0.508 -0.9398)
			(end 0.508 -0.9398)
			(stroke
				(width 0.1524)
				(type default)
			)
			(layer "B.SilkS")
		)
		(fp_line
			(start 0.508 -0.9398)
			(end 0.508 0.9398)
			(stroke
				(width 0.1524)
				(type default)
			)
			(layer "B.SilkS")
		)
		(fp_rect
			(start 0.508 0.9398)
			(end -0.508 -0.9398)
			(stroke
				(width 0)
				(type default)
			)
			(fill no)
			(layer "B.CrtYd")
		)
		(fp_rect
			(start 0.508 0.9398)
			(end -0.508 -0.9398)
			(stroke
				(width 0)
				(type default)
			)
			(fill no)
			(layer "B.Fab")
		)
		(pad "1" smd custom
			(at 0 -0.4445 180)
			(size 0.1397 0.1397)
			(layers "B.Cu" "B.Mask" "B.Paste")
			(net "BMC_I2C_SDA_10")
			(options
				(clearance outline)
				(anchor circle)
			)
			(primitives
				(gr_poly
					(pts
						(arc
							(start -0.1778 0.2794)
							(mid -0.249642 0.249642)
							(end -0.2794 0.1778)
						)
						(arc
							(start -0.2794 -0.1778)
							(mid -0.249642 -0.249642)
							(end -0.1778 -0.2794)
						)
						(arc
							(start 0.1778 -0.2794)
							(mid 0.249642 -0.249642)
							(end 0.2794 -0.1778)
						)
						(arc
							(start 0.2794 0.1778)
							(mid 0.249642 0.249642)
							(end 0.1778 0.2794)
						)
					)
					(width 0)
					(fill yes)
				)
			)
		)
		(pad "2" smd custom
			(at 0 0.4445 180)
			(size 0.1397 0.1397)
			(layers "B.Cu" "B.Mask" "B.Paste")
			(net "TEMP_3_SDA")
			(options
				(clearance outline)
				(anchor circle)
			)
			(primitives
				(gr_poly
					(pts
						(arc
							(start -0.1778 0.2794)
							(mid -0.249642 0.249642)
							(end -0.2794 0.1778)
						)
						(arc
							(start -0.2794 -0.1778)
							(mid -0.249642 -0.249642)
							(end -0.1778 -0.2794)
						)
						(arc
							(start 0.1778 -0.2794)
							(mid 0.249642 -0.249642)
							(end 0.2794 -0.1778)
						)
						(arc
							(start 0.2794 0.1778)
							(mid 0.249642 0.249642)
							(end 0.1778 0.2794)
						)
					)
					(width 0)
					(fill yes)
				)
			)
		)
	)
	(footprint ""
		(layer "B.Cu")
		(at 105.30967 -87.9475 -90)
		(property "Reference" "SC1221"
			(at 0 0 90)
			(layer "B.SilkS")
			(hide yes)
			(effects
				(font
					(size 1.27 1.27)
				)
				(justify mirror)
			)
		)
		(property "Value" "SCD1U6D3V1KX-GP"
			(at 2.8321 -1.7399 270)
			(unlocked yes)
			(layer "B.Fab")
			(hide yes)
			(effects
				(font
					(size 1.016 1.016)
					(thickness 0.1524)
				)
				(justify mirror)
			)
		)
		(property "Device Type" "C0201H13"
			(at 2.8321 -3.2639 270)
			(unlocked yes)
			(layer "B.Fab")
			(hide yes)
			(effects
				(font
					(size 1.016 1.016)
					(thickness 0.1524)
				)
				(justify mirror)
			)
		)
		(duplicate_pad_numbers_are_jumpers no)
		(fp_rect
			(start 0.2794 0.6477)
			(end -0.2794 -0.6477)
			(stroke
				(width 0)
				(type default)
			)
			(fill no)
			(layer "B.CrtYd")
		)
		(fp_rect
			(start 0.2794 0.6477)
			(end -0.2794 -0.6477)
			(stroke
				(width 0)
				(type default)
			)
			(fill no)
			(layer "B.Fab")
		)
		(pad "1" smd custom
			(at 0 -0.2794 90)
			(size 0.0762 0.0762)
			(layers "B.Cu" "B.Mask" "B.Paste")
			(net "P1V8_E")
			(options
				(clearance outline)
				(anchor circle)
			)
			(primitives
				(gr_poly
					(pts
						(arc
							(start 0.1524 0.127)
							(mid 0.137521 0.162921)
							(end 0.1016 0.1778)
						)
						(arc
							(start -0.1016 0.1778)
							(mid -0.137521 0.162921)
							(end -0.1524 0.127)
						)
						(arc
							(start -0.1524 -0.127)
							(mid -0.137521 -0.162921)
							(end -0.1016 -0.1778)
						)
						(arc
							(start 0.1016 -0.1778)
							(mid 0.137521 -0.162921)
							(end 0.1524 -0.127)
						)
					)
					(width 0)
					(fill yes)
				)
			)
		)
		(pad "2" smd custom
			(at 0 0.2794 90)
			(size 0.0762 0.0762)
			(layers "B.Cu" "B.Mask" "B.Paste")
			(net "GND")
			(options
				(clearance outline)
				(anchor circle)
			)
			(primitives
				(gr_poly
					(pts
						(arc
							(start 0.1524 0.127)
							(mid 0.137521 0.162921)
							(end 0.1016 0.1778)
						)
						(arc
							(start -0.1016 0.1778)
							(mid -0.137521 0.162921)
							(end -0.1524 0.127)
						)
						(arc
							(start -0.1524 -0.127)
							(mid -0.137521 -0.162921)
							(end -0.1016 -0.1778)
						)
						(arc
							(start 0.1016 -0.1778)
							(mid 0.137521 -0.162921)
							(end 0.1524 -0.127)
						)
					)
					(width 0)
					(fill yes)
				)
			)
		)
	)
	(footprint ""
		(layer "B.Cu")
		(at 116.545106 -37.5666)
		(property "Reference" "STP23"
			(at 0 0 0)
			(layer "B.SilkS")
			(hide yes)
			(effects
				(font
					(size 1.27 1.27)
				)
				(justify mirror)
			)
		)
		(property "Value" "TPAD28"
			(at -0.0127 -1.8034 0)
			(unlocked yes)
			(layer "B.Fab")
			(hide yes)
			(effects
				(font
					(size 1.016 1.016)
					(thickness 0.1524)
				)
				(justify mirror)
			)
		)
		(property "Device Type" "TPAD28"
			(at -0.0127 -3.3274 0)
			(unlocked yes)
			(layer "B.Fab")
			(hide yes)
			(effects
				(font
					(size 1.016 1.016)
					(thickness 0.1524)
				)
				(justify mirror)
			)
		)
		(duplicate_pad_numbers_are_jumpers no)
		(fp_poly
			(pts
				(arc
					(start 0.3556 0)
					(mid -0.3556 0)
					(end 0.3556 0)
				)
			)
			(stroke
				(width 0)
				(type default)
			)
			(fill no)
			(layer "B.CrtYd")
		)
		(fp_poly
			(pts
				(arc
					(start 0.6096 0)
					(mid -0.6096 0)
					(end 0.6096 0)
				)
			)
			(stroke
				(width 0)
				(type default)
			)
			(fill no)
			(layer "B.Fab")
		)
		(pad "1" smd circle
			(at 0 0 180)
			(size 0.7112 0.7112)
			(layers "B.Cu" "B.Mask" "B.Paste")
			(net "IOC_GPIO_37")
		)
	)
)
